(kicad_pcb
	(version 20221018)
	(generator pcbnew)
	(general
    (thickness 1.62)
  )
	(paper "A4")
	(title_block
    (title "ECP5 - Datacenter Secure Control Module (DC-SCM)")
    (date "2024-07-01")
    (rev "1.2.1")
		(comment 9 "footprints 142-149 of 506")
	)
	(layers
    (0 "F.Cu" signal)
    (1 "In1.Cu" power)
    (2 "In2.Cu" signal)
    (3 "In3.Cu" power)
    (4 "In4.Cu" power)
    (5 "In5.Cu" signal)
    (6 "In6.Cu" power)
    (31 "B.Cu" signal)
    (32 "B.Adhes" user "B.Adhesive")
    (33 "F.Adhes" user "F.Adhesive")
    (34 "B.Paste" user)
    (35 "F.Paste" user)
    (36 "B.SilkS" user "B.Silkscreen")
    (37 "F.SilkS" user "F.Silkscreen")
    (38 "B.Mask" user)
    (39 "F.Mask" user)
    (40 "Dwgs.User" user "User.Drawings")
    (41 "Cmts.User" user "User.Comments")
    (42 "Eco1.User" user "User.Eco1")
    (43 "Eco2.User" user "User.Eco2")
    (44 "Edge.Cuts" user)
    (45 "Margin" user)
    (46 "B.CrtYd" user "B.Courtyard")
    (47 "F.CrtYd" user "F.Courtyard")
    (48 "B.Fab" user)
    (49 "F.Fab" user)
  )
	(footprint "antmicro-footprints:C_0402_1005Metric" (layer "F.Cu")
    (at 77.4 83.935 180)
    (descr "Capacitor SMD 0402")
    (tags "capacitor SMD 0402")
    (property "Author" "Antmicro")
    (property "Dielectric" "")
    (property "License" "Apache-2.0")
    (property "MPN" "CC0402MRX5R5BB106")
    (property "Manufacturer" "YAGEO")
    (property "Public" "False")
    (property "Sheetfile" "power-supply.kicad_sch")
    (property "Sheetname" "Power supply")
    (property "Val" "10u")
    (property "Voltage" "")
    (property "ki_description" "SMD Multilayer Ceramic Capacitor, 10 µF, 6.3 V, 0402 [1005 Metric], ± 20%, X5R, CC Series")
    (property "ki_keywords" "0402, SMT, CAPACITOR, PASSIVE, MLCC, CERAMIC")
    (attr smd)
    (fp_text reference "C116" (at 1.18 1.13 180) (layer "F.SilkS")
        (effects (font (size 0.7 0.7) (thickness 0.127)))
    )
    (fp_text value "C_10u_0402" (at 0 1.17) (layer "F.Fab")
        (effects (font (size 1 1) (thickness 0.15)))
    )
    (fp_text user "${REFERENCE}" (at 0 0) (layer "F.Fab")
        (effects (font (size 0.25 0.25) (thickness 0.04)))
    )
    (fp_text user "Author: Antmicro" (at -0.939 3.399 180) (layer "F.Fab") hide
        (effects (font (size 0.7 0.7) (thickness 0.15)) (justify left bottom))
    )
    (fp_text user "License: Apache-2.0" (at -0.939 5.799 180) (layer "F.Fab") hide
        (effects (font (size 0.7 0.7) (thickness 0.15)) (justify left bottom))
    )
    (fp_rect (start -0.925 -0.47) (end 0.925 0.47)
      (stroke (width 0.05) (type default)) (fill none) (layer "F.CrtYd"))
    (fp_line (start -0.494 -0.25) (end 0.504 -0.25)
      (stroke (width 0.15) (type solid)) (layer "F.Fab"))
    (fp_line (start -0.494 0.248) (end -0.494 -0.25)
      (stroke (width 0.15) (type solid)) (layer "F.Fab"))
    (fp_line (start 0.504 -0.25) (end 0.504 0.248)
      (stroke (width 0.15) (type solid)) (layer "F.Fab"))
    (fp_line (start 0.504 0.248) (end -0.494 0.248)
      (stroke (width 0.15) (type solid)) (layer "F.Fab"))
    (pad "1" smd roundrect (at -0.48 0 180) (size 0.59 0.64) (layers "F.Cu" "F.Paste" "F.Mask") (roundrect_rratio 0.25)
      (net 1 "GND") (pintype "passive"))
    (pad "2" smd roundrect (at 0.48 0 180) (size 0.59 0.64) (layers "F.Cu" "F.Paste" "F.Mask") (roundrect_rratio 0.25)
      (net 11 "VCC5V0") (pintype "passive"))
  )
	(footprint "antmicro-footprints:C_0402_1005Metric" (layer "F.Cu")
    (at 71.3 83.945 180)
    (descr "Capacitor SMD 0402")
    (tags "capacitor SMD 0402")
    (property "Author" "Antmicro")
    (property "Dielectric" "")
    (property "License" "Apache-2.0")
    (property "MPN" "CC0402MRX5R5BB106")
    (property "Manufacturer" "YAGEO")
    (property "Public" "False")
    (property "Sheetfile" "power-supply.kicad_sch")
    (property "Sheetname" "Power supply")
    (property "Val" "10u")
    (property "Voltage" "")
    (property "ki_description" "SMD Multilayer Ceramic Capacitor, 10 µF, 6.3 V, 0402 [1005 Metric], ± 20%, X5R, CC Series")
    (property "ki_keywords" "0402, SMT, CAPACITOR, PASSIVE, MLCC, CERAMIC")
    (attr smd)
    (fp_text reference "C117" (at 1.8 0.96 180) (layer "F.SilkS")
        (effects (font (size 0.7 0.7) (thickness 0.127)))
    )
    (fp_text value "C_10u_0402" (at 0 1.17) (layer "F.Fab")
        (effects (font (size 1 1) (thickness 0.15)))
    )
    (fp_text user "License: Apache-2.0" (at -0.939 5.799 180) (layer "F.Fab") hide
        (effects (font (size 0.7 0.7) (thickness 0.15)) (justify left bottom))
    )
    (fp_text user "Author: Antmicro" (at -0.939 3.399 180) (layer "F.Fab") hide
        (effects (font (size 0.7 0.7) (thickness 0.15)) (justify left bottom))
    )
    (fp_text user "${REFERENCE}" (at 0 0) (layer "F.Fab")
        (effects (font (size 0.25 0.25) (thickness 0.04)))
    )
    (fp_rect (start -0.925 -0.47) (end 0.925 0.47)
      (stroke (width 0.05) (type default)) (fill none) (layer "F.CrtYd"))
    (fp_line (start -0.494 -0.25) (end 0.504 -0.25)
      (stroke (width 0.15) (type solid)) (layer "F.Fab"))
    (fp_line (start -0.494 0.248) (end -0.494 -0.25)
      (stroke (width 0.15) (type solid)) (layer "F.Fab"))
    (fp_line (start 0.504 -0.25) (end 0.504 0.248)
      (stroke (width 0.15) (type solid)) (layer "F.Fab"))
    (fp_line (start 0.504 0.248) (end -0.494 0.248)
      (stroke (width 0.15) (type solid)) (layer "F.Fab"))
    (pad "1" smd roundrect (at -0.48 0 180) (size 0.59 0.64) (layers "F.Cu" "F.Paste" "F.Mask") (roundrect_rratio 0.25)
      (net 1 "GND") (pintype "passive"))
    (pad "2" smd roundrect (at 0.48 0 180) (size 0.59 0.64) (layers "F.Cu" "F.Paste" "F.Mask") (roundrect_rratio 0.25)
      (net 11 "VCC5V0") (pintype "passive"))
  )
	(footprint "antmicro-footprints:C_0402_1005Metric" (layer "F.Cu")
    (at 83.34 83.945)
    (descr "Capacitor SMD 0402")
    (tags "capacitor SMD 0402")
    (property "Author" "Antmicro")
    (property "Dielectric" "")
    (property "License" "Apache-2.0")
    (property "MPN" "CC0402MRX5R5BB106")
    (property "Manufacturer" "YAGEO")
    (property "Public" "False")
    (property "Sheetfile" "power-supply.kicad_sch")
    (property "Sheetname" "Power supply")
    (property "Val" "10u")
    (property "Voltage" "")
    (property "ki_description" "SMD Multilayer Ceramic Capacitor, 10 µF, 6.3 V, 0402 [1005 Metric], ± 20%, X5R, CC Series")
    (property "ki_keywords" "0402, SMT, CAPACITOR, PASSIVE, MLCC, CERAMIC")
    (attr smd)
    (fp_text reference "C114" (at -1 -1.84 90) (layer "F.SilkS")
        (effects (font (size 0.7 0.7) (thickness 0.127)))
    )
    (fp_text value "C_10u_0402" (at 0 1.17) (layer "F.Fab")
        (effects (font (size 1 1) (thickness 0.15)))
    )
    (fp_text user "${REFERENCE}" (at 0 0) (layer "F.Fab")
        (effects (font (size 0.25 0.25) (thickness 0.04)))
    )
    (fp_text user "License: Apache-2.0" (at -0.939 5.799) (layer "F.Fab") hide
        (effects (font (size 0.7 0.7) (thickness 0.15)) (justify left bottom))
    )
    (fp_text user "Author: Antmicro" (at -0.939 3.399) (layer "F.Fab") hide
        (effects (font (size 0.7 0.7) (thickness 0.15)) (justify left bottom))
    )
    (fp_rect (start -0.925 -0.47) (end 0.925 0.47)
      (stroke (width 0.05) (type default)) (fill none) (layer "F.CrtYd"))
    (fp_line (start -0.494 -0.25) (end 0.504 -0.25)
      (stroke (width 0.15) (type solid)) (layer "F.Fab"))
    (fp_line (start -0.494 0.248) (end -0.494 -0.25)
      (stroke (width 0.15) (type solid)) (layer "F.Fab"))
    (fp_line (start 0.504 -0.25) (end 0.504 0.248)
      (stroke (width 0.15) (type solid)) (layer "F.Fab"))
    (fp_line (start 0.504 0.248) (end -0.494 0.248)
      (stroke (width 0.15) (type solid)) (layer "F.Fab"))
    (pad "1" smd roundrect (at -0.48 0) (size 0.59 0.64) (layers "F.Cu" "F.Paste" "F.Mask") (roundrect_rratio 0.25)
      (net 11 "VCC5V0") (pintype "passive"))
    (pad "2" smd roundrect (at 0.48 0) (size 0.59 0.64) (layers "F.Cu" "F.Paste" "F.Mask") (roundrect_rratio 0.25)
      (net 1 "GND") (pintype "passive"))
  )
	(footprint "antmicro-footprints:R_0603_1608Metric" (layer "F.Cu")
    (at 92.6 87.2 90)
    (descr "Resistor SMD 0603")
    (tags "resistor SMD 0603")
    (property "Author" "Antmicro")
    (property "Current" "1A")
    (property "License" "Apache-2.0")
    (property "MPN" "CR0603-J/-000ELF")
    (property "Manufacturer" "Bourns")
    (property "Public" "False")
    (property "Sheetfile" "power-supply.kicad_sch")
    (property "Sheetname" "Power supply")
    (property "Tolerance" "")
    (property "Val" "0R")
    (property "ki_description" "Zero Ohm Resistor, Jumper, 0603 [1608 Metric], Thick Film, 100 mW, 1 A, Surface Mount Device, CR")
    (property "ki_keywords" "0603, SMT, RESISTOR, PASSIVE")
    (attr smd)
    (fp_text reference "R145" (at -0.21 1.19 90) (layer "F.SilkS")
        (effects (font (size 0.7 0.7) (thickness 0.127)))
    )
    (fp_text value "R_0R_0603" (at 0 1.9 90) (layer "F.Fab")
        (effects (font (size 1 1) (thickness 0.15)))
    )
    (fp_text user "License: Apache-2.0" (at -1.25 5.9 90) (layer "F.Fab") hide
        (effects (font (size 0.7 0.7) (thickness 0.15)) (justify left bottom))
    )
    (fp_text user "Author: Antmicro" (at -1.25 4.9 90) (layer "F.Fab") hide
        (effects (font (size 0.7 0.7) (thickness 0.15)) (justify left bottom))
    )
    (fp_text user "${REFERENCE}" (at -1.25 3.898 90) (layer "F.Fab") hide
        (effects (font (size 0.7 0.7) (thickness 0.15)) (justify left bottom))
    )
    (fp_line (start -0.15 -0.4) (end 0.15 -0.4)
      (stroke (width 0.15) (type solid)) (layer "F.SilkS"))
    (fp_line (start -0.15 0.4) (end 0.15 0.4)
      (stroke (width 0.15) (type solid)) (layer "F.SilkS"))
    (fp_rect (start -1.25 -0.65) (end 1.25 0.65)
      (stroke (width 0.05) (type solid)) (fill none) (layer "F.CrtYd"))
    (fp_rect (start -0.8 -0.4) (end 0.8 0.4)
      (stroke (width 0.15) (type solid)) (fill none) (layer "F.Fab"))
    (pad "1" smd roundrect (at -0.7 0 90) (size 0.8 1) (layers "F.Cu" "F.Paste" "F.Mask") (roundrect_rratio 0.2)
      (net 225 "VCC2V5") (pintype "passive"))
    (pad "2" smd roundrect (at 0.7 0 90) (size 0.8 1) (layers "F.Cu" "F.Paste" "F.Mask") (roundrect_rratio 0.2)
      (net 359 "Net-(C122-Pad2)") (pintype "passive"))
  )
	(footprint "antmicro-footprints:L_Vishay-IHLP-1212AE" (layer "F.Cu")
    (at 85.25 81.55)
    (property "Author" "Antmicro")
    (property "IMax" "6.7 A")
    (property "ISat" "6.7 A")
    (property "License" "Apache-2.0")
    (property "MPN" "IHLP1212AEERR47M11")
    (property "Manufacturer" "Vishay")
    (property "Public" "False")
    (property "Sheetfile" "power-supply.kicad_sch")
    (property "Sheetname" "Power supply")
    (property "Size" "3.0x3.0")
    (property "Val" "470n/6.7A")
    (property "ki_description" "Power Inductor (SMT), 470 nH, 6.7 A, Shielded, 6.7 A")
    (property "ki_keywords" "SMT, INDUCTOR, PASSIVE")
    (attr smd)
    (fp_text reference "L3" (at -2.35 -1.155) (layer "F.SilkS")
        (effects (font (size 0.7 0.7) (thickness 0.127)))
    )
    (fp_text value "IHLP1212AEERR47M11" (at 0 0 270) (layer "F.SilkS") hide
        (effects (font (size 1.524 1.524) (thickness 0.05)))
    )
    (fp_text user "Author: Antmicro" (at -2.35 6.6) (layer "F.Fab") hide
        (effects (font (size 0.7 0.7) (thickness 0.15)) (justify left bottom))
    )
    (fp_text user "${REFERENCE}" (at -2.35 5.4) (layer "F.Fab") hide
        (effects (font (size 0.7 0.7) (thickness 0.15)) (justify left bottom))
    )
    (fp_text user "License: Apache-2.0" (at -2.35 7.8) (layer "F.Fab") hide
        (effects (font (size 0.7 0.7) (thickness 0.15)) (justify left bottom))
    )
    (fp_line (start -1.647 -1.6) (end 1.653 -1.6)
      (stroke (width 0.15) (type solid)) (layer "F.SilkS"))
    (fp_line (start -1.647 -0.9) (end -1.647 -1.6)
      (stroke (width 0.15) (type solid)) (layer "F.SilkS"))
    (fp_line (start -1.647 1.6) (end -1.647 0.9)
      (stroke (width 0.15) (type solid)) (layer "F.SilkS"))
    (fp_line (start 1.653 -1.6) (end 1.653 -0.9)
      (stroke (width 0.15) (type solid)) (layer "F.SilkS"))
    (fp_line (start 1.653 0.9) (end 1.653 1.601)
      (stroke (width 0.15) (type solid)) (layer "F.SilkS"))
    (fp_line (start 1.653 1.601) (end -1.647 1.6)
      (stroke (width 0.15) (type solid)) (layer "F.SilkS"))
    (fp_rect (start -2.35 -1.85) (end 2.35 1.85)
      (stroke (width 0.05) (type solid)) (fill none) (layer "F.CrtYd"))
    (fp_rect (start -1.803 -1.601) (end 1.803 1.601)
      (stroke (width 0.15) (type solid)) (fill none) (layer "F.Fab"))
    (pad "1" smd roundrect (at -1.35 0) (size 1.5 1.2) (layers "F.Cu" "F.Paste" "F.Mask") (roundrect_rratio 0.1)
      (net 389 "Net-(U17-SW)") (pintype "passive"))
    (pad "2" smd roundrect (at 1.35 0) (size 1.5 1.2) (layers "F.Cu" "F.Paste" "F.Mask") (roundrect_rratio 0.1)
      (net 355 "Net-(C118-Pad2)") (pintype "passive"))
  )
	(footprint "antmicro-footprints:R_0603_1608Metric" (layer "F.Cu")
    (at 86.6 87.2 90)
    (descr "Resistor SMD 0603")
    (tags "resistor SMD 0603")
    (property "Author" "Antmicro")
    (property "Current" "1A")
    (property "License" "Apache-2.0")
    (property "MPN" "CR0603-J/-000ELF")
    (property "Manufacturer" "Bourns")
    (property "Public" "False")
    (property "Sheetfile" "power-supply.kicad_sch")
    (property "Sheetname" "Power supply")
    (property "Tolerance" "")
    (property "Val" "0R")
    (property "ki_description" "Zero Ohm Resistor, Jumper, 0603 [1608 Metric], Thick Film, 100 mW, 1 A, Surface Mount Device, CR")
    (property "ki_keywords" "0603, SMT, RESISTOR, PASSIVE")
    (attr smd)
    (fp_text reference "R141" (at -2.435 0.01 90) (layer "F.SilkS")
        (effects (font (size 0.7 0.7) (thickness 0.127)))
    )
    (fp_text value "R_0R_0603" (at 0 1.9 90) (layer "F.Fab")
        (effects (font (size 1 1) (thickness 0.15)))
    )
    (fp_text user "Author: Antmicro" (at -1.25 4.9 90) (layer "F.Fab") hide
        (effects (font (size 0.7 0.7) (thickness 0.15)) (justify left bottom))
    )
    (fp_text user "${REFERENCE}" (at -1.25 3.898 90) (layer "F.Fab") hide
        (effects (font (size 0.7 0.7) (thickness 0.15)) (justify left bottom))
    )
    (fp_text user "License: Apache-2.0" (at -1.25 5.9 90) (layer "F.Fab") hide
        (effects (font (size 0.7 0.7) (thickness 0.15)) (justify left bottom))
    )
    (fp_line (start -0.15 -0.4) (end 0.15 -0.4)
      (stroke (width 0.15) (type solid)) (layer "F.SilkS"))
    (fp_line (start -0.15 0.4) (end 0.15 0.4)
      (stroke (width 0.15) (type solid)) (layer "F.SilkS"))
    (fp_rect (start -1.25 -0.65) (end 1.25 0.65)
      (stroke (width 0.05) (type solid)) (fill none) (layer "F.CrtYd"))
    (fp_rect (start -0.8 -0.4) (end 0.8 0.4)
      (stroke (width 0.15) (type solid)) (fill none) (layer "F.Fab"))
    (pad "1" smd roundrect (at -0.7 0 90) (size 0.8 1) (layers "F.Cu" "F.Paste" "F.Mask") (roundrect_rratio 0.2)
      (net 2 "VCC3V3") (pintype "passive"))
    (pad "2" smd roundrect (at 0.7 0 90) (size 0.8 1) (layers "F.Cu" "F.Paste" "F.Mask") (roundrect_rratio 0.2)
      (net 355 "Net-(C118-Pad2)") (pintype "passive"))
  )
	(footprint "antmicro-footprints:C_0402_1005Metric" (layer "F.Cu")
    (at 90.65 89.75)
    (descr "Capacitor SMD 0402")
    (tags "capacitor SMD 0402")
    (property "Author" "Antmicro")
    (property "Dielectric" "C0G")
    (property "License" "Apache-2.0")
    (property "MPN" "C0402C121J5GACTU")
    (property "Manufacturer" "KEMET")
    (property "Public" "False")
    (property "Sheetfile" "power-supply.kicad_sch")
    (property "Sheetname" "Power supply")
    (property "Val" "120p")
    (property "Voltage" "100V")
    (property "ki_description" "120 pF ±2% 100V Ceramic Capacitor C0G, NP0 0402 (1005 Metric)")
    (property "ki_keywords" "0402, SMT, CAPACITOR, PASSIVE, CERAMIC, MLCC")
    (attr smd)
    (fp_text reference "C122" (at 0.05 0.825) (layer "F.SilkS")
        (effects (font (size 0.7 0.7) (thickness 0.127)))
    )
    (fp_text value "C_120p_0402" (at 0 1.17) (layer "F.Fab")
        (effects (font (size 1 1) (thickness 0.15)))
    )
    (fp_text user "${REFERENCE}" (at 0 0) (layer "F.Fab")
        (effects (font (size 0.25 0.25) (thickness 0.04)))
    )
    (fp_text user "License: Apache-2.0" (at -0.939 5.799) (layer "F.Fab") hide
        (effects (font (size 0.7 0.7) (thickness 0.15)) (justify left bottom))
    )
    (fp_text user "Author: Antmicro" (at -0.939 3.399) (layer "F.Fab") hide
        (effects (font (size 0.7 0.7) (thickness 0.15)) (justify left bottom))
    )
    (fp_rect (start -0.925 -0.47) (end 0.925 0.47)
      (stroke (width 0.05) (type default)) (fill none) (layer "F.CrtYd"))
    (fp_line (start -0.494 -0.25) (end 0.504 -0.25)
      (stroke (width 0.15) (type solid)) (layer "F.Fab"))
    (fp_line (start -0.494 0.248) (end -0.494 -0.25)
      (stroke (width 0.15) (type solid)) (layer "F.Fab"))
    (fp_line (start 0.504 -0.25) (end 0.504 0.248)
      (stroke (width 0.15) (type solid)) (layer "F.Fab"))
    (fp_line (start 0.504 0.248) (end -0.494 0.248)
      (stroke (width 0.15) (type solid)) (layer "F.Fab"))
    (pad "1" smd roundrect (at -0.48 0) (size 0.59 0.64) (layers "F.Cu" "F.Paste" "F.Mask") (roundrect_rratio 0.25)
      (net 301 "Net-(U16-FB)") (pintype "passive"))
    (pad "2" smd roundrect (at 0.48 0) (size 0.59 0.64) (layers "F.Cu" "F.Paste" "F.Mask") (roundrect_rratio 0.25)
      (net 359 "Net-(C122-Pad2)") (pintype "passive"))
  )
	(footprint "antmicro-footprints:C_0402_1005Metric" (layer "F.Cu")
    (at 92.05 83.965)
    (descr "Capacitor SMD 0402")
    (tags "capacitor SMD 0402")
    (property "Author" "Antmicro")
    (property "Dielectric" "")
    (property "License" "Apache-2.0")
    (property "MPN" "CC0402MRX5R5BB106")
    (property "Manufacturer" "YAGEO")
    (property "Public" "False")
    (property "Sheetfile" "power-supply.kicad_sch")
    (property "Sheetname" "Power supply")
    (property "Val" "10u")
    (property "Voltage" "")
    (property "ki_description" "SMD Multilayer Ceramic Capacitor, 10 µF, 6.3 V, 0402 [1005 Metric], ± 20%, X5R, CC Series")
    (property "ki_keywords" "0402, SMT, CAPACITOR, PASSIVE, MLCC, CERAMIC")
    (attr smd)
    (fp_text reference "C127" (at 2.3 0.69) (layer "F.SilkS")
        (effects (font (size 0.7 0.7) (thickness 0.127)))
    )
    (fp_text value "C_10u_0402" (at 0 1.17) (layer "F.Fab")
        (effects (font (size 1 1) (thickness 0.15)))
    )
    (fp_text user "Author: Antmicro" (at -0.939 3.399) (layer "F.Fab") hide
        (effects (font (size 0.7 0.7) (thickness 0.15)) (justify left bottom))
    )
    (fp_text user "${REFERENCE}" (at 0 0) (layer "F.Fab")
        (effects (font (size 0.25 0.25) (thickness 0.04)))
    )
    (fp_text user "License: Apache-2.0" (at -0.939 5.799) (layer "F.Fab") hide
        (effects (font (size 0.7 0.7) (thickness 0.15)) (justify left bottom))
    )
    (fp_rect (start -0.925 -0.47) (end 0.925 0.47)
      (stroke (width 0.05) (type default)) (fill none) (layer "F.CrtYd"))
    (fp_line (start -0.494 -0.25) (end 0.504 -0.25)
      (stroke (width 0.15) (type solid)) (layer "F.Fab"))
    (fp_line (start -0.494 0.248) (end -0.494 -0.25)
      (stroke (width 0.15) (type solid)) (layer "F.Fab"))
    (fp_line (start 0.504 -0.25) (end 0.504 0.248)
      (stroke (width 0.15) (type solid)) (layer "F.Fab"))
    (fp_line (start 0.504 0.248) (end -0.494 0.248)
      (stroke (width 0.15) (type solid)) (layer "F.Fab"))
    (pad "1" smd roundrect (at -0.48 0) (size 0.59 0.64) (layers "F.Cu" "F.Paste" "F.Mask") (roundrect_rratio 0.25)
      (net 1 "GND") (pintype "passive"))
    (pad "2" smd roundrect (at 0.48 0) (size 0.59 0.64) (layers "F.Cu" "F.Paste" "F.Mask") (roundrect_rratio 0.25)
      (net 359 "Net-(C122-Pad2)") (pintype "passive"))
  )
)
